# BASEBOARD_FAB2 (Tioga Pass) — schematic netlist excerpt (pin names and nets, part order shuffled) for the footprints in the layout excerpt that follows; sources: Cadence DE-HDL packaged netlist, KiCad conversion of Wiwynn_Tioga_Pass_MB.brd

EU7G1  PXM1310B  IC  pkg QFN  page 215
  BPWM1  = NC
  DNC(0)  = NC
  APWM3  = NC
  APWM2  = VR_PVDDQ_ABC_PWM2
  APWM1  = VR_PVDDQ_ABC_PWM1
  SDA  = SMB_VR_STBY_LVC3_SDA
  SCL  = SMB_VR_STBY_LVC3_SCL
  RESET_N  = NC
  AVRRDY  = PWRGD_PVDDQ_ABC_R
  AVREN  = VR_PVDDQ_ABC_VREN
  VRHOT_N  = IRQ_PVDDQ_ABC_VRHOT_LVT3_R_N
  PINALRT_N  = NC
  MP0  = PU_VR_PVDDQ_ABC_FAULT1
  MP1  = TP_PVDDQ_ABC_MP1
  VCLK  = SVID_CLK_PVDDQ_ABC
  VDIO  = SVID_VDIO_PVDDQ_ABC
  VALRT_N  = SVID_ALERT_PVDDQ_ABC
  MP2  = TP_PVDDQ_ABC_MP2
  AVSEN  = VR_PVDDQ_ABC_AVSP
  AVREF  = VSENSE_PVDDQ_ABC_N
  AIREF1  = VR_PVDDQ_ABC_AIREF1
  AISEN1  = ISENSE_PVDDQ_ABC_PH1_IMON
  AIREF2  = VR_PVDDQ_ABC_AIREF2
  AISEN2  = ISENSE_PVDDQ_ABC_PH2_IMON
  AIREF3  = NC
  AISEN3  = NC
  GND  = GND
  DNC(1)  = NC
  BVSEN  = NC
  BVREF  = NC
  BIREF1  = NC
  BISEN1  = GND
  XADDR2  = VR_PVDDQ_ABC_XADDR2
  BTSEN  = NC
  ATSEN  = A_TSENSE_PVDDQ_ABC
  XADDR1  = VR_PVDDQ_ABC_XADDR1
  VINSEN  = VR_PVDDQ_ABC_VINSEN
  IINSEN  = VR_PVDDQ_ABC_AIINSEN
  VDD  = VR_PVDDQ_ABC_VDD
  VD12  = VR_PVDDQ_ABC_VD12
  THPAD  = GND

(kicad_pcb
	(version 20260206)
	(generator "pcbnew")
	(generator_version "10.0")
	(general
		(thickness 1.6)
		(legacy_teardrops no)
	)
	(paper "A4")
	(title_block
		(title "Wiwynn_Tioga_Pass_MB.brd")
		(comment 1 "Tioga Pass / footprint 467 of 4770 (EU7G1), pads 35-41 of 41")
	)
	(layers
		(0 "F.Cu" signal "TOP")
		(4 "In1.Cu" signal "L2GND")
		(6 "In2.Cu" signal "L3")
		(8 "In3.Cu" signal "L4GND")
		(10 "In4.Cu" signal "L5")
		(12 "In5.Cu" signal "L6GND")
		(14 "In6.Cu" signal "L7VCC")
		(16 "In7.Cu" signal "L8VCC")
		(18 "In8.Cu" signal "L9GND")
		(20 "In9.Cu" signal "L10")
		(22 "In10.Cu" signal "L11GND")
		(24 "In11.Cu" signal "L12")
		(26 "In12.Cu" signal "L13GND")
		(2 "B.Cu" signal "BOTTOM")
		(9 "F.Adhes" user "F.Adhesive")
		(11 "B.Adhes" user "B.Adhesive")
		(13 "F.Paste" user "Package Geometry/Pastemask Top")
		(15 "B.Paste" user "Package Geometry/Pastemask Bottom")
		(5 "F.SilkS" user "Ref Des/Silkscreen Top")
		(7 "B.SilkS" user "Ref Des/Silkscreen Bottom")
		(1 "F.Mask" user "Board Geometry/Soldermask Top")
		(3 "B.Mask" user "Board Geometry/Soldermask Bottom")
		(17 "Dwgs.User" user "User.Drawings")
		(19 "Cmts.User" user "User.Comments")
		(21 "Eco1.User" user "User.Eco1")
		(23 "Eco2.User" user "User.Eco2")
		(25 "Edge.Cuts" user "Board Geometry/Outline")
		(27 "Margin" user)
		(31 "F.CrtYd" user "Package Geometry/Place Bound Top")
		(29 "B.CrtYd" user "Package Geometry/Place Bound Bottom")
		(35 "F.Fab" user "Ref Des/Assembly Top")
		(33 "B.Fab" user "Ref Des/Assembly Bottom")
	)
	(footprint ""
		(layer "F.Cu")
		(at 344.678 -15.367 -90)
		(property "Reference" "EU7G1"
			(at 1.27 4.03733 90)
			(unlocked yes)
			(layer "F.SilkS")
			(effects
				(font
					(size 0.7874 0.5842)
					(thickness 0.1524)
				)
				(justify left)
			)
		)
		(property "Value" ""
			(at 0 0 270)
			(layer "F.Fab")
			(effects
				(font
					(size 1.27 1.27)
				)
			)
		)
		(duplicate_pad_numbers_are_jumpers no)
		(pad "35" smd custom
			(at 0.199898 -2.4511 270)
			(size 0.0508 0.0508)
			(layers "F.Cu" "F.Mask" "F.Paste")
			(net "A_TSENSE_PVDDQ_ABC")
			(options
				(clearance outline)
				(anchor circle)
			)
			(primitives
				(gr_poly
					(pts
						(arc
							(start 0.1016 0.254)
							(mid 0 0.3556)
							(end -0.1016 0.254)
						)
						(xy -0.1016 -0.3556) (xy 0.1016 -0.3556)
					)
					(width 0)
					(fill yes)
				)
			)
		)
		(pad "36" smd custom
			(at -0.199898 -2.4511 270)
			(size 0.0508 0.0508)
			(layers "F.Cu" "F.Mask" "F.Paste")
			(net "VR_PVDDQ_ABC_XADDR1")
			(options
				(clearance outline)
				(anchor circle)
			)
			(primitives
				(gr_poly
					(pts
						(arc
							(start 0.1016 0.254)
							(mid 0 0.3556)
							(end -0.1016 0.254)
						)
						(xy -0.1016 -0.3556) (xy 0.1016 -0.3556)
					)
					(width 0)
					(fill yes)
				)
			)
		)
		(pad "37" smd custom
			(at -0.599948 -2.4511 270)
			(size 0.0508 0.0508)
			(layers "F.Cu" "F.Mask" "F.Paste")
			(net "VR_PVDDQ_ABC_VINSEN")
			(options
				(clearance outline)
				(anchor circle)
			)
			(primitives
				(gr_poly
					(pts
						(arc
							(start 0.1016 0.254)
							(mid 0 0.3556)
							(end -0.1016 0.254)
						)
						(xy -0.1016 -0.3556) (xy 0.1016 -0.3556)
					)
					(width 0)
					(fill yes)
				)
			)
		)
		(pad "38" smd custom
			(at -0.999998 -2.4511 270)
			(size 0.0508 0.0508)
			(layers "F.Cu" "F.Mask" "F.Paste")
			(net "VR_PVDDQ_ABC_AIINSEN")
			(options
				(clearance outline)
				(anchor circle)
			)
			(primitives
				(gr_poly
					(pts
						(arc
							(start 0.1016 0.254)
							(mid 0 0.3556)
							(end -0.1016 0.254)
						)
						(xy -0.1016 -0.3556) (xy 0.1016 -0.3556)
					)
					(width 0)
					(fill yes)
				)
			)
		)
		(pad "39" smd custom
			(at -1.400048 -2.4511 270)
			(size 0.0508 0.0508)
			(layers "F.Cu" "F.Mask" "F.Paste")
			(net "VR_PVDDQ_ABC_VDD")
			(options
				(clearance outline)
				(anchor circle)
			)
			(primitives
				(gr_poly
					(pts
						(arc
							(start 0.1016 0.254)
							(mid 0 0.3556)
							(end -0.1016 0.254)
						)
						(xy -0.1016 -0.3556) (xy 0.1016 -0.3556)
					)
					(width 0)
					(fill yes)
				)
			)
		)
		(pad "40" smd custom
			(at -1.800098 -2.4511 270)
			(size 0.0508 0.0508)
			(layers "F.Cu" "F.Mask" "F.Paste")
			(net "VR_PVDDQ_ABC_VD12")
			(options
				(clearance outline)
				(anchor circle)
			)
			(primitives
				(gr_poly
					(pts
						(arc
							(start 0.1016 0.254)
							(mid 0 0.3556)
							(end -0.1016 0.254)
						)
						(xy -0.1016 -0.3556) (xy 0.1016 -0.3556)
					)
					(width 0)
					(fill yes)
				)
			)
		)
		(pad "41" smd rect
			(at 0 0 270)
			(size 3.683 3.683)
			(layers "F.Cu" "F.Mask" "F.Paste")
			(net "GND")
		)
	)
)
